(kicad_pcb
	(version 20260206)
	(generator "pcbnew")
	(generator_version "10.0")
	(general
		(thickness 1.6)
		(legacy_teardrops no)
	)
	(paper "A4")
	(title_block
		(title "Bryce Canyon_IOM_IOC_16318-2_OCP.brd")
		(comment 1 "Bryce Canyon / footprints 1512-1520 of 1605")
	)
	(layers
		(0 "F.Cu" signal "TOP")
		(4 "In1.Cu" signal "L2GND")
		(6 "In2.Cu" signal "L3")
		(8 "In3.Cu" signal "L4VCC")
		(10 "In4.Cu" signal "L5VCC")
		(12 "In5.Cu" signal "L6")
		(14 "In6.Cu" signal "L7GND")
		(2 "B.Cu" signal "BOTTOM")
		(9 "F.Adhes" user "F.Adhesive")
		(11 "B.Adhes" user "B.Adhesive")
		(13 "F.Paste" user "Package Geometry/Pastemask Top")
		(15 "B.Paste" user "Package Geometry/Pastemask Bottom")
		(5 "F.SilkS" user "Ref Des/Silkscreen Top")
		(7 "B.SilkS" user "Ref Des/Silkscreen Bottom")
		(1 "F.Mask" user "Board Geometry/Soldermask Top")
		(3 "B.Mask" user "Board Geometry/Soldermask Bottom")
		(17 "Dwgs.User" user "User.Drawings")
		(19 "Cmts.User" user "User.Comments")
		(21 "Eco1.User" user "User.Eco1")
		(23 "Eco2.User" user "User.Eco2")
		(25 "Edge.Cuts" user "Board Geometry/Outline")
		(27 "Margin" user)
		(31 "F.CrtYd" user "Package Geometry/Place Bound Top")
		(29 "B.CrtYd" user "Package Geometry/Place Bound Bottom")
		(35 "F.Fab" user "Ref Des/Assembly Top")
		(33 "B.Fab" user "Ref Des/Assembly Bottom")
	)
	(footprint ""
		(layer "B.Cu")
		(at 50.1396 -139.446)
		(property "Reference" "TP72"
			(at 0 0 0)
			(layer "B.SilkS")
			(hide yes)
			(effects
				(font
					(size 1.27 1.27)
				)
				(justify mirror)
			)
		)
		(property "Value" "TPAD28-2-GP"
			(at 0.0127 -1.6637 0)
			(unlocked yes)
			(layer "B.Fab")
			(hide yes)
			(effects
				(font
					(size 1.016 1.016)
					(thickness 0.1524)
				)
				(justify mirror)
			)
		)
		(property "Device Type" "TPAD28"
			(at 0.0127 -3.1877 0)
			(unlocked yes)
			(layer "B.Fab")
			(hide yes)
			(effects
				(font
					(size 1.016 1.016)
					(thickness 0.1524)
				)
				(justify mirror)
			)
		)
		(duplicate_pad_numbers_are_jumpers no)
		(fp_poly
			(pts
				(arc
					(start 0.3556 0)
					(mid -0.3556 0)
					(end 0.3556 0)
				)
			)
			(stroke
				(width 0)
				(type default)
			)
			(fill no)
			(layer "B.CrtYd")
		)
		(fp_poly
			(pts
				(arc
					(start 0.6096 0)
					(mid -0.6096 0)
					(end 0.6096 0)
				)
			)
			(stroke
				(width 0)
				(type default)
			)
			(fill no)
			(layer "B.Fab")
		)
		(pad "1" smd circle
			(at 0 0 180)
			(size 0.7112 0.7112)
			(layers "B.Cu" "B.Mask" "B.Paste")
			(net "TP_BMC_GPIOI1")
		)
	)
	(footprint ""
		(layer "B.Cu")
		(at 169.7736 -76.5302 -90)
		(property "Reference" "L16"
			(at 0 0 90)
			(layer "B.SilkS")
			(hide yes)
			(effects
				(font
					(size 1.27 1.27)
				)
				(justify mirror)
			)
		)
		(property "Value" "MPZ2012S601AT-GP"
			(at 0 -4.2418 270)
			(unlocked yes)
			(layer "B.Fab")
			(hide yes)
			(effects
				(font
					(size 1.016 1.016)
					(thickness 0.1524)
				)
				(justify mirror)
			)
		)
		(property "Device Type" "L805H42"
			(at 0 -5.7912 270)
			(unlocked yes)
			(layer "B.Fab")
			(hide yes)
			(effects
				(font
					(size 1.016 1.016)
					(thickness 0.1524)
				)
				(justify mirror)
			)
		)
		(duplicate_pad_numbers_are_jumpers no)
		(fp_line
			(start -0.889 1.7018)
			(end 0.889 1.7018)
			(stroke
				(width 0.1524)
				(type default)
			)
			(layer "B.SilkS")
		)
		(fp_line
			(start 0.889 1.7018)
			(end 0.889 -1.7018)
			(stroke
				(width 0.1524)
				(type default)
			)
			(layer "B.SilkS")
		)
		(fp_line
			(start -0.889 -1.7018)
			(end -0.889 1.7018)
			(stroke
				(width 0.1524)
				(type default)
			)
			(layer "B.SilkS")
		)
		(fp_line
			(start 0.889 -1.7018)
			(end -0.889 -1.7018)
			(stroke
				(width 0.1524)
				(type default)
			)
			(layer "B.SilkS")
		)
		(fp_rect
			(start 0.9652 1.778)
			(end -0.9652 -1.778)
			(stroke
				(width 0)
				(type default)
			)
			(fill no)
			(layer "B.CrtYd")
		)
		(fp_rect
			(start 0.9652 1.778)
			(end -0.9652 -1.778)
			(stroke
				(width 0)
				(type default)
			)
			(fill no)
			(layer "B.Fab")
		)
		(pad "1" smd rect
			(at 0 -0.9652 90)
			(size 1.397 1.143)
			(layers "B.Cu" "B.Mask" "B.Paste")
			(net "PLL_VDD")
		)
		(pad "2" smd rect
			(at 0 0.9652 90)
			(size 1.397 1.143)
			(layers "B.Cu" "B.Mask" "B.Paste")
			(net "P1V8")
		)
	)
	(footprint ""
		(layer "B.Cu")
		(at 80.08366 -172.76318 180)
		(property "Reference" "R451"
			(at 0 0 0)
			(layer "B.SilkS")
			(hide yes)
			(effects
				(font
					(size 1.27 1.27)
				)
				(justify mirror)
			)
		)
		(property "Value" "10KR2F-2-GP"
			(at -0.064008 -3.993896 180)
			(unlocked yes)
			(layer "B.Fab")
			(hide yes)
			(effects
				(font
					(size 1.016 1.016)
					(thickness 0.1524)
				)
				(justify mirror)
			)
		)
		(property "Device Type" "R402H16"
			(at -0.064008 -5.517896 180)
			(unlocked yes)
			(layer "B.Fab")
			(hide yes)
			(effects
				(font
					(size 1.016 1.016)
					(thickness 0.1524)
				)
				(justify mirror)
			)
		)
		(duplicate_pad_numbers_are_jumpers no)
		(fp_line
			(start 0.508 -0.9398)
			(end 0.508 0.9398)
			(stroke
				(width 0.1524)
				(type default)
			)
			(layer "B.SilkS")
		)
		(fp_line
			(start -0.508 -0.9398)
			(end 0.508 -0.9398)
			(stroke
				(width 0.1524)
				(type default)
			)
			(layer "B.SilkS")
		)
		(fp_rect
			(start 0.508 0.9398)
			(end -0.508 -0.9398)
			(stroke
				(width 0)
				(type default)
			)
			(fill no)
			(layer "B.CrtYd")
		)
		(fp_rect
			(start 0.508 0.9398)
			(end -0.508 -0.9398)
			(stroke
				(width 0)
				(type default)
			)
			(fill no)
			(layer "B.Fab")
		)
		(pad "1" smd custom
			(at 0 -0.4445)
			(size 0.1397 0.1397)
			(layers "B.Cu" "B.Mask" "B.Paste")
			(net "EXP_UART_EN_R")
			(options
				(clearance outline)
				(anchor circle)
			)
			(primitives
				(gr_poly
					(pts
						(arc
							(start -0.1778 0.2794)
							(mid -0.249642 0.249642)
							(end -0.2794 0.1778)
						)
						(arc
							(start -0.2794 -0.1778)
							(mid -0.249642 -0.249642)
							(end -0.1778 -0.2794)
						)
						(arc
							(start 0.1778 -0.2794)
							(mid 0.249642 -0.249642)
							(end 0.2794 -0.1778)
						)
						(arc
							(start 0.2794 0.1778)
							(mid 0.249642 0.249642)
							(end 0.1778 0.2794)
						)
					)
					(width 0)
					(fill yes)
				)
			)
		)
		(pad "2" smd custom
			(at 0 0.4445)
			(size 0.1397 0.1397)
			(layers "B.Cu" "B.Mask" "B.Paste")
			(net "GND")
			(options
				(clearance outline)
				(anchor circle)
			)
			(primitives
				(gr_poly
					(pts
						(arc
							(start -0.1778 0.2794)
							(mid -0.249642 0.249642)
							(end -0.2794 0.1778)
						)
						(arc
							(start -0.2794 -0.1778)
							(mid -0.249642 -0.249642)
							(end -0.1778 -0.2794)
						)
						(arc
							(start 0.1778 -0.2794)
							(mid 0.249642 -0.249642)
							(end 0.2794 -0.1778)
						)
						(arc
							(start 0.2794 0.1778)
							(mid 0.249642 0.249642)
							(end 0.1778 0.2794)
						)
					)
					(width 0)
					(fill yes)
				)
			)
		)
	)
	(footprint ""
		(layer "B.Cu")
		(at 58.900568 -138.905234 -90)
		(property "Reference" "TP69"
			(at 0 0 90)
			(layer "B.SilkS")
			(hide yes)
			(effects
				(font
					(size 1.27 1.27)
				)
				(justify mirror)
			)
		)
		(property "Value" "TPAD28-2-GP"
			(at 0.0127 -1.6637 270)
			(unlocked yes)
			(layer "B.Fab")
			(hide yes)
			(effects
				(font
					(size 1.016 1.016)
					(thickness 0.1524)
				)
				(justify mirror)
			)
		)
		(property "Device Type" "TPAD28"
			(at 0.0127 -3.1877 270)
			(unlocked yes)
			(layer "B.Fab")
			(hide yes)
			(effects
				(font
					(size 1.016 1.016)
					(thickness 0.1524)
				)
				(justify mirror)
			)
		)
		(duplicate_pad_numbers_are_jumpers no)
		(fp_poly
			(pts
				(arc
					(start 0 -0.3556)
					(mid 0 0.3556)
					(end 0 -0.3556)
				)
			)
			(stroke
				(width 0)
				(type default)
			)
			(fill no)
			(layer "B.CrtYd")
		)
		(fp_poly
			(pts
				(arc
					(start 0 -0.6096)
					(mid 0 0.6096)
					(end 0 -0.6096)
				)
			)
			(stroke
				(width 0)
				(type default)
			)
			(fill no)
			(layer "B.Fab")
		)
		(pad "1" smd circle
			(at 0 0 90)
			(size 0.7112 0.7112)
			(layers "B.Cu" "B.Mask" "B.Paste")
			(net "TP_BMC_GPIOG6")
		)
	)
	(footprint ""
		(layer "B.Cu")
		(at 10.20191 -135.290052 90)
		(property "Reference" "R256"
			(at 0 0 90)
			(layer "B.SilkS")
			(hide yes)
			(effects
				(font
					(size 1.27 1.27)
				)
				(justify mirror)
			)
		)
		(property "Value" "120R2F-GP"
			(at -0.064008 -3.993896 90)
			(unlocked yes)
			(layer "B.Fab")
			(hide yes)
			(effects
				(font
					(size 1.016 1.016)
					(thickness 0.1524)
				)
				(justify mirror)
			)
		)
		(property "Device Type" "R402H16"
			(at -0.064008 -5.517896 90)
			(unlocked yes)
			(layer "B.Fab")
			(hide yes)
			(effects
				(font
					(size 1.016 1.016)
					(thickness 0.1524)
				)
				(justify mirror)
			)
		)
		(duplicate_pad_numbers_are_jumpers no)
		(fp_line
			(start 0.508 -0.9398)
			(end 0.508 0.9398)
			(stroke
				(width 0.1524)
				(type default)
			)
			(layer "B.SilkS")
		)
		(fp_line
			(start -0.508 -0.9398)
			(end 0.508 -0.9398)
			(stroke
				(width 0.1524)
				(type default)
			)
			(layer "B.SilkS")
		)
		(fp_rect
			(start 0.508 0.9398)
			(end -0.508 -0.9398)
			(stroke
				(width 0)
				(type default)
			)
			(fill no)
			(layer "B.CrtYd")
		)
		(fp_rect
			(start 0.508 0.9398)
			(end -0.508 -0.9398)
			(stroke
				(width 0)
				(type default)
			)
			(fill no)
			(layer "B.Fab")
		)
		(pad "1" smd custom
			(at 0 -0.4445 270)
			(size 0.1397 0.1397)
			(layers "B.Cu" "B.Mask" "B.Paste")
			(net "GND")
			(options
				(clearance outline)
				(anchor circle)
			)
			(primitives
				(gr_poly
					(pts
						(arc
							(start -0.1778 0.2794)
							(mid -0.249642 0.249642)
							(end -0.2794 0.1778)
						)
						(arc
							(start -0.2794 -0.1778)
							(mid -0.249642 -0.249642)
							(end -0.1778 -0.2794)
						)
						(arc
							(start 0.1778 -0.2794)
							(mid 0.249642 -0.249642)
							(end 0.2794 -0.1778)
						)
						(arc
							(start 0.2794 0.1778)
							(mid 0.249642 0.249642)
							(end 0.1778 0.2794)
						)
					)
					(width 0)
					(fill yes)
				)
			)
		)
		(pad "2" smd custom
			(at 0 0.4445 270)
			(size 0.1397 0.1397)
			(layers "B.Cu" "B.Mask" "B.Paste")
			(net "MEMA_11")
			(options
				(clearance outline)
				(anchor circle)
			)
			(primitives
				(gr_poly
					(pts
						(arc
							(start -0.1778 0.2794)
							(mid -0.249642 0.249642)
							(end -0.2794 0.1778)
						)
						(arc
							(start -0.2794 -0.1778)
							(mid -0.249642 -0.249642)
							(end -0.1778 -0.2794)
						)
						(arc
							(start 0.1778 -0.2794)
							(mid 0.249642 -0.249642)
							(end 0.2794 -0.1778)
						)
						(arc
							(start 0.2794 0.1778)
							(mid 0.249642 0.249642)
							(end 0.1778 0.2794)
						)
					)
					(width 0)
					(fill yes)
				)
			)
		)
	)
	(footprint ""
		(layer "B.Cu")
		(at 59.563 -163.1442 -90)
		(property "Reference" "R403"
			(at 0 0 90)
			(layer "B.SilkS")
			(hide yes)
			(effects
				(font
					(size 1.27 1.27)
				)
				(justify mirror)
			)
		)
		(property "Value" "330R2F-GP"
			(at -0.064008 -3.993896 270)
			(unlocked yes)
			(layer "B.Fab")
			(hide yes)
			(effects
				(font
					(size 1.016 1.016)
					(thickness 0.1524)
				)
				(justify mirror)
			)
		)
		(property "Device Type" "R402H16"
			(at -0.064008 -5.517896 270)
			(unlocked yes)
			(layer "B.Fab")
			(hide yes)
			(effects
				(font
					(size 1.016 1.016)
					(thickness 0.1524)
				)
				(justify mirror)
			)
		)
		(duplicate_pad_numbers_are_jumpers no)
		(fp_line
			(start -0.508 -0.9398)
			(end 0.508 -0.9398)
			(stroke
				(width 0.1524)
				(type default)
			)
			(layer "B.SilkS")
		)
		(fp_line
			(start 0.508 -0.9398)
			(end 0.508 0.9398)
			(stroke
				(width 0.1524)
				(type default)
			)
			(layer "B.SilkS")
		)
		(fp_rect
			(start 0.508 0.9398)
			(end -0.508 -0.9398)
			(stroke
				(width 0)
				(type default)
			)
			(fill no)
			(layer "B.CrtYd")
		)
		(fp_rect
			(start 0.508 0.9398)
			(end -0.508 -0.9398)
			(stroke
				(width 0)
				(type default)
			)
			(fill no)
			(layer "B.Fab")
		)
		(pad "1" smd custom
			(at 0 -0.4445 90)
			(size 0.1397 0.1397)
			(layers "B.Cu" "B.Mask" "B.Paste")
			(net "P1V8")
			(options
				(clearance outline)
				(anchor circle)
			)
			(primitives
				(gr_poly
					(pts
						(arc
							(start -0.1778 0.2794)
							(mid -0.249642 0.249642)
							(end -0.2794 0.1778)
						)
						(arc
							(start -0.2794 -0.1778)
							(mid -0.249642 -0.249642)
							(end -0.1778 -0.2794)
						)
						(arc
							(start 0.1778 -0.2794)
							(mid 0.249642 -0.249642)
							(end 0.2794 -0.1778)
						)
						(arc
							(start 0.2794 0.1778)
							(mid 0.249642 0.249642)
							(end 0.1778 0.2794)
						)
					)
					(width 0)
					(fill yes)
				)
			)
		)
		(pad "2" smd custom
			(at 0 0.4445 90)
			(size 0.1397 0.1397)
			(layers "B.Cu" "B.Mask" "B.Paste")
			(net "ADC_P1V8")
			(options
				(clearance outline)
				(anchor circle)
			)
			(primitives
				(gr_poly
					(pts
						(arc
							(start -0.1778 0.2794)
							(mid -0.249642 0.249642)
							(end -0.2794 0.1778)
						)
						(arc
							(start -0.2794 -0.1778)
							(mid -0.249642 -0.249642)
							(end -0.1778 -0.2794)
						)
						(arc
							(start 0.1778 -0.2794)
							(mid 0.249642 -0.249642)
							(end 0.2794 -0.1778)
						)
						(arc
							(start 0.2794 0.1778)
							(mid 0.249642 0.249642)
							(end 0.1778 0.2794)
						)
					)
					(width 0)
					(fill yes)
				)
			)
		)
	)
	(footprint ""
		(layer "B.Cu")
		(at 190.199518 -81.153 180)
		(property "Reference" "C301"
			(at 0 0 0)
			(layer "B.SilkS")
			(hide yes)
			(effects
				(font
					(size 1.27 1.27)
				)
				(justify mirror)
			)
		)
		(property "Value" "SCD22U10V1KX-GP"
			(at 2.8321 -1.7399 180)
			(unlocked yes)
			(layer "B.Fab")
			(hide yes)
			(effects
				(font
					(size 1.016 1.016)
					(thickness 0.1524)
				)
				(justify mirror)
			)
		)
		(property "Device Type" "C0201H13"
			(at 2.8321 -3.2639 180)
			(unlocked yes)
			(layer "B.Fab")
			(hide yes)
			(effects
				(font
					(size 1.016 1.016)
					(thickness 0.1524)
				)
				(justify mirror)
			)
		)
		(duplicate_pad_numbers_are_jumpers no)
		(fp_rect
			(start 0.2794 0.6477)
			(end -0.2794 -0.6477)
			(stroke
				(width 0)
				(type default)
			)
			(fill no)
			(layer "B.CrtYd")
		)
		(fp_rect
			(start 0.2794 0.6477)
			(end -0.2794 -0.6477)
			(stroke
				(width 0)
				(type default)
			)
			(fill no)
			(layer "B.Fab")
		)
		(pad "1" smd custom
			(at 0 -0.2794)
			(size 0.0762 0.0762)
			(layers "B.Cu" "B.Mask" "B.Paste")
			(net "PCIE_IOM_TO_COMP_14_DP_C")
			(options
				(clearance outline)
				(anchor circle)
			)
			(primitives
				(gr_poly
					(pts
						(arc
							(start 0.1524 0.127)
							(mid 0.137521 0.162921)
							(end 0.1016 0.1778)
						)
						(arc
							(start -0.1016 0.1778)
							(mid -0.137521 0.162921)
							(end -0.1524 0.127)
						)
						(arc
							(start -0.1524 -0.127)
							(mid -0.137521 -0.162921)
							(end -0.1016 -0.1778)
						)
						(arc
							(start 0.1016 -0.1778)
							(mid 0.137521 -0.162921)
							(end 0.1524 -0.127)
						)
					)
					(width 0)
					(fill yes)
				)
			)
		)
		(pad "2" smd custom
			(at 0 0.2794)
			(size 0.0762 0.0762)
			(layers "B.Cu" "B.Mask" "B.Paste")
			(net "PCIE_IOM_TO_COMP_14_DP")
			(options
				(clearance outline)
				(anchor circle)
			)
			(primitives
				(gr_poly
					(pts
						(arc
							(start 0.1524 0.127)
							(mid 0.137521 0.162921)
							(end 0.1016 0.1778)
						)
						(arc
							(start -0.1016 0.1778)
							(mid -0.137521 0.162921)
							(end -0.1524 0.127)
						)
						(arc
							(start -0.1524 -0.127)
							(mid -0.137521 -0.162921)
							(end -0.1016 -0.1778)
						)
						(arc
							(start 0.1016 -0.1778)
							(mid 0.137521 -0.162921)
							(end 0.1524 -0.127)
						)
					)
					(width 0)
					(fill yes)
				)
			)
		)
	)
	(footprint ""
		(layer "B.Cu")
		(at 199.76846 -67.56654 90)
		(property "Reference" "C380"
			(at 0 0 90)
			(layer "B.SilkS")
			(hide yes)
			(effects
				(font
					(size 1.27 1.27)
				)
				(justify mirror)
			)
		)
		(property "Value" "SCD1U6D3V1KX-GP"
			(at 2.8321 -1.7399 90)
			(unlocked yes)
			(layer "B.Fab")
			(hide yes)
			(effects
				(font
					(size 1.016 1.016)
					(thickness 0.1524)
				)
				(justify mirror)
			)
		)
		(property "Device Type" "C0201H13"
			(at 2.8321 -3.2639 90)
			(unlocked yes)
			(layer "B.Fab")
			(hide yes)
			(effects
				(font
					(size 1.016 1.016)
					(thickness 0.1524)
				)
				(justify mirror)
			)
		)
		(duplicate_pad_numbers_are_jumpers no)
		(fp_rect
			(start 0.2794 0.6477)
			(end -0.2794 -0.6477)
			(stroke
				(width 0)
				(type default)
			)
			(fill no)
			(layer "B.CrtYd")
		)
		(fp_rect
			(start 0.2794 0.6477)
			(end -0.2794 -0.6477)
			(stroke
				(width 0)
				(type default)
			)
			(fill no)
			(layer "B.Fab")
		)
		(pad "1" smd custom
			(at 0 -0.2794 270)
			(size 0.0762 0.0762)
			(layers "B.Cu" "B.Mask" "B.Paste")
			(net "SAS0_AVDD")
			(options
				(clearance outline)
				(anchor circle)
			)
			(primitives
				(gr_poly
					(pts
						(arc
							(start 0.1524 0.127)
							(mid 0.137521 0.162921)
							(end 0.1016 0.1778)
						)
						(arc
							(start -0.1016 0.1778)
							(mid -0.137521 0.162921)
							(end -0.1524 0.127)
						)
						(arc
							(start -0.1524 -0.127)
							(mid -0.137521 -0.162921)
							(end -0.1016 -0.1778)
						)
						(arc
							(start 0.1016 -0.1778)
							(mid 0.137521 -0.162921)
							(end 0.1524 -0.127)
						)
					)
					(width 0)
					(fill yes)
				)
			)
		)
		(pad "2" smd custom
			(at 0 0.2794 270)
			(size 0.0762 0.0762)
			(layers "B.Cu" "B.Mask" "B.Paste")
			(net "GND")
			(options
				(clearance outline)
				(anchor circle)
			)
			(primitives
				(gr_poly
					(pts
						(arc
							(start 0.1524 0.127)
							(mid 0.137521 0.162921)
							(end 0.1016 0.1778)
						)
						(arc
							(start -0.1016 0.1778)
							(mid -0.137521 0.162921)
							(end -0.1524 0.127)
						)
						(arc
							(start -0.1524 -0.127)
							(mid -0.137521 -0.162921)
							(end -0.1016 -0.1778)
						)
						(arc
							(start 0.1016 -0.1778)
							(mid 0.137521 -0.162921)
							(end 0.1524 -0.127)
						)
					)
					(width 0)
					(fill yes)
				)
			)
		)
	)
	(footprint ""
		(layer "B.Cu")
		(at 13.2207 -147.3835 -90)
		(property "Reference" "C61"
			(at 0 0 90)
			(layer "B.SilkS")
			(hide yes)
			(effects
				(font
					(size 1.27 1.27)
				)
				(justify mirror)
			)
		)
		(property "Value" "SC1U16V3KX-5GP"
			(at 0 -2.8194 270)
			(unlocked yes)
			(layer "B.Fab")
			(hide yes)
			(effects
				(font
					(size 1.016 1.016)
					(thickness 0.1524)
				)
				(justify mirror)
			)
		)
		(property "Device Type" "C603H36"
			(at 0 -4.3434 270)
			(unlocked yes)
			(layer "B.Fab")
			(hide yes)
			(effects
				(font
					(size 1.016 1.016)
					(thickness 0.1524)
				)
				(justify mirror)
			)
		)
		(duplicate_pad_numbers_are_jumpers no)
		(fp_line
			(start -0.508 0)
			(end 0.508 0)
			(stroke
				(width 0.2032)
				(type default)
			)
			(layer "B.SilkS")
		)
		(fp_rect
			(start 0.5842 1.3335)
			(end -0.5842 -1.3335)
			(stroke
				(width 0)
				(type default)
			)
			(fill no)
			(layer "B.CrtYd")
		)
		(fp_rect
			(start 0.5842 1.3335)
			(end -0.5842 -1.3335)
			(stroke
				(width 0)
				(type default)
			)
			(fill no)
			(layer "B.Fab")
		)
		(pad "1" smd custom
			(at 0 -0.762 90)
			(size 0.2159 0.2159)
			(layers "B.Cu" "B.Mask" "B.Paste")
			(net "P1V2_STBY")
			(options
				(clearance outline)
				(anchor circle)
			)
			(primitives
				(gr_poly
					(pts
						(arc
							(start -0.3302 0.4318)
							(mid -0.402042 0.402042)
							(end -0.4318 0.3302)
						)
						(arc
							(start -0.4318 -0.3302)
							(mid -0.402042 -0.402042)
							(end -0.3302 -0.4318)
						)
						(arc
							(start 0.3302 -0.4318)
							(mid 0.402042 -0.402042)
							(end 0.4318 -0.3302)
						)
						(arc
							(start 0.4318 0.3302)
							(mid 0.402042 0.402042)
							(end 0.3302 0.4318)
						)
					)
					(width 0)
					(fill yes)
				)
			)
		)
		(pad "2" smd custom
			(at 0 0.762 90)
			(size 0.2159 0.2159)
			(layers "B.Cu" "B.Mask" "B.Paste")
			(net "GND")
			(options
				(clearance outline)
				(anchor circle)
			)
			(primitives
				(gr_poly
					(pts
						(arc
							(start -0.3302 0.4318)
							(mid -0.402042 0.402042)
							(end -0.4318 0.3302)
						)
						(arc
							(start -0.4318 -0.3302)
							(mid -0.402042 -0.402042)
							(end -0.3302 -0.4318)
						)
						(arc
							(start 0.3302 -0.4318)
							(mid 0.402042 -0.402042)
							(end 0.4318 -0.3302)
						)
						(arc
							(start 0.4318 0.3302)
							(mid 0.402042 0.402042)
							(end 0.3302 0.4318)
						)
					)
					(width 0)
					(fill yes)
				)
			)
		)
	)
)
